(kicad_pcb
	(version 20260206)
	(generator "pcbnew")
	(generator_version "10.0")
	(general
		(thickness 1.6)
		(legacy_teardrops no)
	)
	(paper "A4")
	(title_block
		(title "01162023_DA0F0TEBIF0_F0T_Expander_BD_F_brd_V02_OCP.brd")
		(comment 1 "Grand Teton / footprints 637-643 of 9728")
	)
	(layers
		(0 "F.Cu" signal "TOP")
		(4 "In1.Cu" signal "GND")
		(6 "In2.Cu" signal "VCC")
		(8 "In3.Cu" signal "VCC1")
		(10 "In4.Cu" signal "GND1")
		(12 "In5.Cu" signal "IN1")
		(14 "In6.Cu" signal "GND2")
		(16 "In7.Cu" signal "IN2")
		(18 "In8.Cu" signal "GND3")
		(20 "In9.Cu" signal "IN3")
		(22 "In10.Cu" signal "GND4")
		(24 "In11.Cu" signal "IN4")
		(26 "In12.Cu" signal "GND5")
		(28 "In13.Cu" signal "IN5")
		(30 "In14.Cu" signal "GND6")
		(32 "In15.Cu" signal "IN6")
		(34 "In16.Cu" signal "GND7")
		(2 "B.Cu" signal "BOTTOM")
		(9 "F.Adhes" user "F.Adhesive")
		(11 "B.Adhes" user "B.Adhesive")
		(13 "F.Paste" user "Package Geometry/Pastemask Top")
		(15 "B.Paste" user "Package Geometry/Pastemask Bottom")
		(5 "F.SilkS" user "Ref Des/Silkscreen Top")
		(7 "B.SilkS" user "Ref Des/Silkscreen Bottom")
		(1 "F.Mask" user "Board Geometry/Soldermask Top")
		(3 "B.Mask" user "Board Geometry/Soldermask Bottom")
		(17 "Dwgs.User" user "User.Drawings")
		(19 "Cmts.User" user "User.Comments")
		(21 "Eco1.User" user "User.Eco1")
		(23 "Eco2.User" user "User.Eco2")
		(25 "Edge.Cuts" user "Board Geometry/Outline")
		(27 "Margin" user)
		(31 "F.CrtYd" user "Package Geometry/Place Bound Top")
		(29 "B.CrtYd" user "Package Geometry/Place Bound Bottom")
		(35 "F.Fab" user "Ref Des/Assembly Top")
		(33 "B.Fab" user "Ref Des/Assembly Bottom")
	)
	(footprint ""
		(layer "F.Cu")
		(at 220.676978 -266.873228 180)
		(property "Reference" "L99"
			(at 0 0 180)
			(layer "F.SilkS")
			(hide yes)
			(effects
				(font
					(size 1.27 1.27)
				)
			)
		)
		(property "Value" ""
			(at 0 0 180)
			(layer "F.Fab")
			(effects
				(font
					(size 1.27 1.27)
				)
			)
		)
		(duplicate_pad_numbers_are_jumpers no)
		(fp_line
			(start 2.248154 4.9911)
			(end 2.248154 1.606296)
			(stroke
				(width 0.1524)
				(type default)
			)
			(layer "F.SilkS")
		)
		(fp_line
			(start 2.248154 -1.580642)
			(end 2.248154 -4.9911)
			(stroke
				(width 0.1524)
				(type default)
			)
			(layer "F.SilkS")
		)
		(fp_line
			(start 2.248154 -4.9911)
			(end -2.248154 -4.9911)
			(stroke
				(width 0.1524)
				(type default)
			)
			(layer "F.SilkS")
		)
		(fp_line
			(start -2.248154 4.9911)
			(end 2.248154 4.9911)
			(stroke
				(width 0.1524)
				(type default)
			)
			(layer "F.SilkS")
		)
		(fp_line
			(start -2.248154 1.617218)
			(end -2.248154 4.9911)
			(stroke
				(width 0.1524)
				(type default)
			)
			(layer "F.SilkS")
		)
		(fp_line
			(start -2.248154 -4.9911)
			(end -2.248154 -1.62179)
			(stroke
				(width 0.1524)
				(type default)
			)
			(layer "F.SilkS")
		)
		(fp_line
			(start 1.700022 0.899922)
			(end 1.700022 -0.899922)
			(stroke
				(width 0.1)
				(type default)
			)
			(layer "F.Fab")
		)
		(fp_line
			(start 1.700022 -0.899922)
			(end -1.700022 -0.899922)
			(stroke
				(width 0.1)
				(type default)
			)
			(layer "F.Fab")
		)
		(fp_line
			(start -1.700022 0.899922)
			(end 1.700022 0.899922)
			(stroke
				(width 0.1)
				(type default)
			)
			(layer "F.Fab")
		)
		(fp_line
			(start -1.700022 -0.899922)
			(end -1.700022 0.899922)
			(stroke
				(width 0.1)
				(type default)
			)
			(layer "F.Fab")
		)
		(pad "1" smd rect
			(at -1.575054 0 180)
			(size 1.1684 9.8044)
			(layers "F.Cu" "F.Mask" "F.Paste")
			(net "P1V25_PEX1")
		)
		(pad "2" smd rect
			(at 1.575054 0 180)
			(size 1.1684 9.8044)
			(layers "F.Cu" "F.Mask" "F.Paste")
			(net "P1V25_SERDES_VDDPLL_PEX1")
		)
	)
	(footprint ""
		(layer "F.Cu")
		(at 151.618442 -250.070874 -90)
		(property "Reference" "R1281"
			(at 0 0 270)
			(layer "F.SilkS")
			(hide yes)
			(effects
				(font
					(size 1.27 1.27)
				)
			)
		)
		(property "Value" ""
			(at 0 0 270)
			(layer "F.Fab")
			(effects
				(font
					(size 1.27 1.27)
				)
			)
		)
		(duplicate_pad_numbers_are_jumpers no)
		(fp_line
			(start -0.7874 0.4064)
			(end -0.7874 -0.4064)
			(stroke
				(width 0.1524)
				(type default)
			)
			(layer "F.SilkS")
		)
		(fp_line
			(start 0.7874 0.4064)
			(end -0.7874 0.4064)
			(stroke
				(width 0.1524)
				(type default)
			)
			(layer "F.SilkS")
		)
		(fp_line
			(start -0.7874 -0.4064)
			(end 0.7874 -0.4064)
			(stroke
				(width 0.1524)
				(type default)
			)
			(layer "F.SilkS")
		)
		(fp_line
			(start 0.7874 -0.4064)
			(end 0.7874 0.4064)
			(stroke
				(width 0.1524)
				(type default)
			)
			(layer "F.SilkS")
		)
		(fp_line
			(start -0.67945 0.3048)
			(end -0.67945 -0.305054)
			(stroke
				(width 0.1)
				(type default)
			)
			(layer "F.Fab")
		)
		(fp_line
			(start -0.12065 0.3048)
			(end -0.67945 0.3048)
			(stroke
				(width 0.1)
				(type default)
			)
			(layer "F.Fab")
		)
		(fp_line
			(start 0.120396 0.3048)
			(end 0.120396 0.2794)
			(stroke
				(width 0.1)
				(type default)
			)
			(layer "F.Fab")
		)
		(fp_line
			(start 0.67945 0.3048)
			(end 0.120396 0.3048)
			(stroke
				(width 0.1)
				(type default)
			)
			(layer "F.Fab")
		)
		(fp_line
			(start -0.12065 0.2794)
			(end -0.12065 0.3048)
			(stroke
				(width 0.1)
				(type default)
			)
			(layer "F.Fab")
		)
		(fp_line
			(start 0.120396 0.2794)
			(end -0.12065 0.2794)
			(stroke
				(width 0.1)
				(type default)
			)
			(layer "F.Fab")
		)
		(fp_line
			(start -0.12065 -0.2794)
			(end 0.12065 -0.2794)
			(stroke
				(width 0.1)
				(type default)
			)
			(layer "F.Fab")
		)
		(fp_line
			(start 0.12065 -0.2794)
			(end 0.12065 -0.3048)
			(stroke
				(width 0.1)
				(type default)
			)
			(layer "F.Fab")
		)
		(fp_line
			(start 0.12065 -0.3048)
			(end 0.67945 -0.3048)
			(stroke
				(width 0.1)
				(type default)
			)
			(layer "F.Fab")
		)
		(fp_line
			(start 0.67945 -0.3048)
			(end 0.67945 0.3048)
			(stroke
				(width 0.1)
				(type default)
			)
			(layer "F.Fab")
		)
		(fp_line
			(start -0.67945 -0.305054)
			(end -0.12065 -0.305054)
			(stroke
				(width 0.1)
				(type default)
			)
			(layer "F.Fab")
		)
		(fp_line
			(start -0.12065 -0.305054)
			(end -0.12065 -0.2794)
			(stroke
				(width 0.1)
				(type default)
			)
			(layer "F.Fab")
		)
		(pad "1" smd circle
			(at -0.40005 0 270)
			(size 0 0)
			(layers "F.Cu" "F.Mask" "F.Paste")
			(net "PEX1_MODE_SEL12")
		)
		(pad "2" smd circle
			(at 0.40005 0 270)
			(size 0 0)
			(layers "F.Cu" "F.Mask" "F.Paste")
			(net "P1V8_PEX")
		)
	)
	(footprint ""
		(layer "F.Cu")
		(at 46.947328 -20.35556)
		(property "Reference" "C3883"
			(at 0 0 0)
			(layer "F.SilkS")
			(hide yes)
			(effects
				(font
					(size 1.27 1.27)
				)
			)
		)
		(property "Value" ""
			(at 0 0 0)
			(layer "F.Fab")
			(effects
				(font
					(size 1.27 1.27)
				)
			)
		)
		(duplicate_pad_numbers_are_jumpers no)
		(fp_line
			(start -0.7874 -0.4064)
			(end 0.7874 -0.4064)
			(stroke
				(width 0.1524)
				(type default)
			)
			(layer "F.SilkS")
		)
		(fp_line
			(start -0.7874 0.4064)
			(end -0.7874 -0.4064)
			(stroke
				(width 0.1524)
				(type default)
			)
			(layer "F.SilkS")
		)
		(fp_line
			(start 0.7874 -0.4064)
			(end 0.7874 0.4064)
			(stroke
				(width 0.1524)
				(type default)
			)
			(layer "F.SilkS")
		)
		(fp_line
			(start 0.7874 0.4064)
			(end -0.7874 0.4064)
			(stroke
				(width 0.1524)
				(type default)
			)
			(layer "F.SilkS")
		)
		(fp_line
			(start -0.67945 -0.305054)
			(end -0.12065 -0.305054)
			(stroke
				(width 0.1)
				(type default)
			)
			(layer "F.Fab")
		)
		(fp_line
			(start -0.67945 0.3048)
			(end -0.67945 -0.305054)
			(stroke
				(width 0.1)
				(type default)
			)
			(layer "F.Fab")
		)
		(fp_line
			(start -0.12065 -0.305054)
			(end -0.12065 -0.2794)
			(stroke
				(width 0.1)
				(type default)
			)
			(layer "F.Fab")
		)
		(fp_line
			(start -0.12065 -0.2794)
			(end 0.12065 -0.2794)
			(stroke
				(width 0.1)
				(type default)
			)
			(layer "F.Fab")
		)
		(fp_line
			(start -0.12065 0.2794)
			(end -0.12065 0.3048)
			(stroke
				(width 0.1)
				(type default)
			)
			(layer "F.Fab")
		)
		(fp_line
			(start -0.12065 0.3048)
			(end -0.67945 0.3048)
			(stroke
				(width 0.1)
				(type default)
			)
			(layer "F.Fab")
		)
		(fp_line
			(start 0.120396 0.2794)
			(end -0.12065 0.2794)
			(stroke
				(width 0.1)
				(type default)
			)
			(layer "F.Fab")
		)
		(fp_line
			(start 0.120396 0.3048)
			(end 0.120396 0.2794)
			(stroke
				(width 0.1)
				(type default)
			)
			(layer "F.Fab")
		)
		(fp_line
			(start 0.12065 -0.3048)
			(end 0.67945 -0.3048)
			(stroke
				(width 0.1)
				(type default)
			)
			(layer "F.Fab")
		)
		(fp_line
			(start 0.12065 -0.2794)
			(end 0.12065 -0.3048)
			(stroke
				(width 0.1)
				(type default)
			)
			(layer "F.Fab")
		)
		(fp_line
			(start 0.67945 -0.3048)
			(end 0.67945 0.3048)
			(stroke
				(width 0.1)
				(type default)
			)
			(layer "F.Fab")
		)
		(fp_line
			(start 0.67945 0.3048)
			(end 0.120396 0.3048)
			(stroke
				(width 0.1)
				(type default)
			)
			(layer "F.Fab")
		)
		(pad "1" smd circle
			(at -0.40005 0)
			(size 0 0)
			(layers "F.Cu" "F.Mask" "F.Paste")
			(net "P12V_SSD1")
		)
		(pad "2" smd circle
			(at 0.40005 0)
			(size 0 0)
			(layers "F.Cu" "F.Mask" "F.Paste")
			(net "GND")
		)
	)
	(footprint ""
		(layer "F.Cu")
		(at 334.151478 -7.591552)
		(property "Reference" "U137"
			(at -1.360678 2.462022 0)
			(unlocked yes)
			(layer "F.SilkS")
			(effects
				(font
					(size 0.7874 0.5842)
					(thickness 0.1524)
				)
				(justify left)
			)
		)
		(property "Value" ""
			(at 0 0 0)
			(layer "F.Fab")
			(effects
				(font
					(size 1.27 1.27)
				)
			)
		)
		(duplicate_pad_numbers_are_jumpers no)
		(fp_line
			(start -1.463548 -1.549908)
			(end -0.787908 -1.549908)
			(stroke
				(width 0.1524)
				(type default)
			)
			(layer "F.SilkS")
		)
		(fp_line
			(start -1.463548 1.549908)
			(end -1.463548 -1.549908)
			(stroke
				(width 0.1524)
				(type default)
			)
			(layer "F.SilkS")
		)
		(fp_line
			(start -0.787908 -1.549908)
			(end 0 -0.762)
			(stroke
				(width 0.1524)
				(type default)
			)
			(layer "F.SilkS")
		)
		(fp_line
			(start 0 -0.762)
			(end 0.762 -1.549908)
			(stroke
				(width 0.1524)
				(type default)
			)
			(layer "F.SilkS")
		)
		(fp_line
			(start 0.762 -1.549908)
			(end 1.463548 -1.549908)
			(stroke
				(width 0.1524)
				(type default)
			)
			(layer "F.SilkS")
		)
		(fp_line
			(start 1.463548 -1.549908)
			(end 1.463548 1.549908)
			(stroke
				(width 0.1524)
				(type default)
			)
			(layer "F.SilkS")
		)
		(fp_line
			(start 1.463548 1.549908)
			(end -1.463548 1.549908)
			(stroke
				(width 0.1524)
				(type default)
			)
			(layer "F.SilkS")
		)
		(fp_poly
			(pts
				(xy -3.4798 -1.359916) (xy -2.86004 -1.050036) (xy -3.4798 -0.740156)
			)
			(stroke
				(width 0)
				(type default)
			)
			(fill yes)
			(layer "F.SilkS")
		)
		(fp_line
			(start -1.549908 -1.549908)
			(end 1.549908 -1.549908)
			(stroke
				(width 0.1)
				(type default)
			)
			(layer "F.Fab")
		)
		(fp_line
			(start -1.549908 1.549908)
			(end -1.549908 -1.549908)
			(stroke
				(width 0.1)
				(type default)
			)
			(layer "F.Fab")
		)
		(fp_line
			(start 1.549908 -1.549908)
			(end 1.549908 1.549908)
			(stroke
				(width 0.1)
				(type default)
			)
			(layer "F.Fab")
		)
		(fp_line
			(start 1.549908 1.549908)
			(end -1.549908 1.549908)
			(stroke
				(width 0.1)
				(type default)
			)
			(layer "F.Fab")
		)
		(fp_poly
			(pts
				(xy -3.4798 -1.359916) (xy -2.86004 -1.050036) (xy -3.4798 -0.740156)
			)
			(stroke
				(width 0)
				(type default)
			)
			(fill yes)
			(layer "F.Fab")
		)
		(pad "1" smd rect
			(at -2.175002 -1.050036 90)
			(size 0.6096 1.1684)
			(layers "F.Cu" "F.Mask" "F.Paste")
			(net "P3V3_SSD11")
		)
		(pad "2" smd rect
			(at -2.175002 -0.32512 90)
			(size 0.4318 1.1684)
			(layers "F.Cu" "F.Mask" "F.Paste")
			(net "SMB_ISO_SSD11_SCL")
		)
		(pad "3" smd rect
			(at -2.175002 0.32512 90)
			(size 0.4318 1.1684)
			(layers "F.Cu" "F.Mask" "F.Paste")
			(net "SMB_ISO_SSD11_SDA")
		)
		(pad "4" smd rect
			(at -2.175002 1.050036 90)
			(size 0.6096 1.1684)
			(layers "F.Cu" "F.Mask" "F.Paste")
			(net "GND")
		)
		(pad "5" smd rect
			(at 2.175002 1.050036 90)
			(size 0.6096 1.1684)
			(layers "F.Cu" "F.Mask" "F.Paste")
			(net "SMB_SSD11_ISO_EN")
		)
		(pad "6" smd rect
			(at 2.175002 0.32512 90)
			(size 0.4318 1.1684)
			(layers "F.Cu" "F.Mask" "F.Paste")
			(net "SMB_BIC_I2C9_MUX1_SSD11_R_SDA")
		)
		(pad "7" smd rect
			(at 2.175002 -0.32512 90)
			(size 0.4318 1.1684)
			(layers "F.Cu" "F.Mask" "F.Paste")
			(net "SMB_BIC_I2C9_MUX1_SSD11_R_SCL")
		)
		(pad "8" smd rect
			(at 2.175002 -1.050036 90)
			(size 0.6096 1.1684)
			(layers "F.Cu" "F.Mask" "F.Paste")
			(net "P3V3_AUX")
		)
	)
	(footprint ""
		(layer "F.Cu")
		(at 386.90804 -159.4104 180)
		(property "Reference" "R308"
			(at 0 0 180)
			(layer "F.SilkS")
			(hide yes)
			(effects
				(font
					(size 1.27 1.27)
				)
			)
		)
		(property "Value" ""
			(at 0 0 180)
			(layer "F.Fab")
			(effects
				(font
					(size 1.27 1.27)
				)
			)
		)
		(duplicate_pad_numbers_are_jumpers no)
		(fp_line
			(start 0.7874 0.4064)
			(end -0.7874 0.4064)
			(stroke
				(width 0.1524)
				(type default)
			)
			(layer "F.SilkS")
		)
		(fp_line
			(start 0.7874 -0.4064)
			(end 0.7874 0.4064)
			(stroke
				(width 0.1524)
				(type default)
			)
			(layer "F.SilkS")
		)
		(fp_line
			(start -0.7874 0.4064)
			(end -0.7874 -0.4064)
			(stroke
				(width 0.1524)
				(type default)
			)
			(layer "F.SilkS")
		)
		(fp_line
			(start -0.7874 -0.4064)
			(end 0.7874 -0.4064)
			(stroke
				(width 0.1524)
				(type default)
			)
			(layer "F.SilkS")
		)
		(fp_line
			(start 0.67945 0.3048)
			(end 0.120396 0.3048)
			(stroke
				(width 0.1)
				(type default)
			)
			(layer "F.Fab")
		)
		(fp_line
			(start 0.67945 -0.3048)
			(end 0.67945 0.3048)
			(stroke
				(width 0.1)
				(type default)
			)
			(layer "F.Fab")
		)
		(fp_line
			(start 0.12065 -0.2794)
			(end 0.12065 -0.3048)
			(stroke
				(width 0.1)
				(type default)
			)
			(layer "F.Fab")
		)
		(fp_line
			(start 0.12065 -0.3048)
			(end 0.67945 -0.3048)
			(stroke
				(width 0.1)
				(type default)
			)
			(layer "F.Fab")
		)
		(fp_line
			(start 0.120396 0.3048)
			(end 0.120396 0.2794)
			(stroke
				(width 0.1)
				(type default)
			)
			(layer "F.Fab")
		)
		(fp_line
			(start 0.120396 0.2794)
			(end -0.12065 0.2794)
			(stroke
				(width 0.1)
				(type default)
			)
			(layer "F.Fab")
		)
		(fp_line
			(start -0.12065 0.3048)
			(end -0.67945 0.3048)
			(stroke
				(width 0.1)
				(type default)
			)
			(layer "F.Fab")
		)
		(fp_line
			(start -0.12065 0.2794)
			(end -0.12065 0.3048)
			(stroke
				(width 0.1)
				(type default)
			)
			(layer "F.Fab")
		)
		(fp_line
			(start -0.12065 -0.2794)
			(end 0.12065 -0.2794)
			(stroke
				(width 0.1)
				(type default)
			)
			(layer "F.Fab")
		)
		(fp_line
			(start -0.12065 -0.305054)
			(end -0.12065 -0.2794)
			(stroke
				(width 0.1)
				(type default)
			)
			(layer "F.Fab")
		)
		(fp_line
			(start -0.67945 0.3048)
			(end -0.67945 -0.305054)
			(stroke
				(width 0.1)
				(type default)
			)
			(layer "F.Fab")
		)
		(fp_line
			(start -0.67945 -0.305054)
			(end -0.12065 -0.305054)
			(stroke
				(width 0.1)
				(type default)
			)
			(layer "F.Fab")
		)
		(pad "1" smd circle
			(at -0.40005 0 180)
			(size 0 0)
			(layers "F.Cu" "F.Mask" "F.Paste")
			(net "NIC6_MAIN_PWR_EN_R")
		)
		(pad "2" smd circle
			(at 0.40005 0 180)
			(size 0 0)
			(layers "F.Cu" "F.Mask" "F.Paste")
			(net "NIC6_MAIN_PWR_EN")
		)
	)
	(footprint ""
		(layer "F.Cu")
		(at 454.66889 -258.331208 -90)
		(property "Reference" "R6553"
			(at 0 0 270)
			(layer "F.SilkS")
			(hide yes)
			(effects
				(font
					(size 1.27 1.27)
				)
			)
		)
		(property "Value" ""
			(at 0 0 270)
			(layer "F.Fab")
			(effects
				(font
					(size 1.27 1.27)
				)
			)
		)
		(duplicate_pad_numbers_are_jumpers no)
		(fp_line
			(start -0.7874 0.4064)
			(end -0.7874 -0.4064)
			(stroke
				(width 0.1524)
				(type default)
			)
			(layer "F.SilkS")
		)
		(fp_line
			(start 0.7874 0.4064)
			(end -0.7874 0.4064)
			(stroke
				(width 0.1524)
				(type default)
			)
			(layer "F.SilkS")
		)
		(fp_line
			(start -0.7874 -0.4064)
			(end 0.7874 -0.4064)
			(stroke
				(width 0.1524)
				(type default)
			)
			(layer "F.SilkS")
		)
		(fp_line
			(start 0.7874 -0.4064)
			(end 0.7874 0.4064)
			(stroke
				(width 0.1524)
				(type default)
			)
			(layer "F.SilkS")
		)
		(fp_line
			(start -0.67945 0.3048)
			(end -0.67945 -0.305054)
			(stroke
				(width 0.1)
				(type default)
			)
			(layer "F.Fab")
		)
		(fp_line
			(start -0.12065 0.3048)
			(end -0.67945 0.3048)
			(stroke
				(width 0.1)
				(type default)
			)
			(layer "F.Fab")
		)
		(fp_line
			(start 0.120396 0.3048)
			(end 0.120396 0.2794)
			(stroke
				(width 0.1)
				(type default)
			)
			(layer "F.Fab")
		)
		(fp_line
			(start 0.67945 0.3048)
			(end 0.120396 0.3048)
			(stroke
				(width 0.1)
				(type default)
			)
			(layer "F.Fab")
		)
		(fp_line
			(start -0.12065 0.2794)
			(end -0.12065 0.3048)
			(stroke
				(width 0.1)
				(type default)
			)
			(layer "F.Fab")
		)
		(fp_line
			(start 0.120396 0.2794)
			(end -0.12065 0.2794)
			(stroke
				(width 0.1)
				(type default)
			)
			(layer "F.Fab")
		)
		(fp_line
			(start -0.12065 -0.2794)
			(end 0.12065 -0.2794)
			(stroke
				(width 0.1)
				(type default)
			)
			(layer "F.Fab")
		)
		(fp_line
			(start 0.12065 -0.2794)
			(end 0.12065 -0.3048)
			(stroke
				(width 0.1)
				(type default)
			)
			(layer "F.Fab")
		)
		(fp_line
			(start 0.12065 -0.3048)
			(end 0.67945 -0.3048)
			(stroke
				(width 0.1)
				(type default)
			)
			(layer "F.Fab")
		)
		(fp_line
			(start 0.67945 -0.3048)
			(end 0.67945 0.3048)
			(stroke
				(width 0.1)
				(type default)
			)
			(layer "F.Fab")
		)
		(fp_line
			(start -0.67945 -0.305054)
			(end -0.12065 -0.305054)
			(stroke
				(width 0.1)
				(type default)
			)
			(layer "F.Fab")
		)
		(fp_line
			(start -0.12065 -0.305054)
			(end -0.12065 -0.2794)
			(stroke
				(width 0.1)
				(type default)
			)
			(layer "F.Fab")
		)
		(pad "1" smd circle
			(at -0.40005 0 270)
			(size 0 0)
			(layers "F.Cu" "F.Mask" "F.Paste")
			(net "P1V25_SERDES_VDDPLL_PEX3")
		)
		(pad "2" smd circle
			(at 0.40005 0 270)
			(size 0 0)
			(layers "F.Cu" "F.Mask" "F.Paste")
			(net "P1V25_SERDES_VDDPLL_PEX3_C2")
		)
	)
	(footprint ""
		(layer "F.Cu")
		(at 226.115118 -5.999988)
		(property "Reference" "H63"
			(at -4.574794 -5.022342 0)
			(unlocked yes)
			(layer "F.SilkS")
			(effects
				(font
					(size 0.7874 0.5842)
					(thickness 0.1524)
				)
				(justify left)
			)
		)
		(property "Value" ""
			(at 0 0 0)
			(layer "F.Fab")
			(effects
				(font
					(size 1.27 1.27)
				)
			)
		)
		(duplicate_pad_numbers_are_jumpers no)
		(pad "1" thru_hole circle
			(at 0 0)
			(size 10.0076 10.0076)
			(drill 5.6134)
			(layers "*.Cu" "*.Mask")
			(remove_unused_layers no)
			(net "GND")
			(clearance -1.9431)
		)
	)
)
